(kicad_pcb
	(version 20260206)
	(generator "pcbnew")
	(generator_version "10.0")
	(general
		(thickness 1.6)
		(legacy_teardrops no)
	)
	(paper "A4")
	(title_block
		(title "03242023_DA0F0TMBIJ0_F0T_Motherboard_J_brd_V01_OCP.brd")
		(comment 1 "Grand Teton / footprint 3039 of 6105 (U2), pads 1275-1381 of 4677")
	)
	(layers
		(0 "F.Cu" signal "TOP")
		(4 "In1.Cu" signal "GND")
		(6 "In2.Cu" signal "IN1")
		(8 "In3.Cu" signal "GND1")
		(10 "In4.Cu" signal "IN2")
		(12 "In5.Cu" signal "GND2")
		(14 "In6.Cu" signal "IN3")
		(16 "In7.Cu" signal "GND3")
		(18 "In8.Cu" signal "VCC")
		(20 "In9.Cu" signal "VCC1")
		(22 "In10.Cu" signal "GND4")
		(24 "In11.Cu" signal "IN4")
		(26 "In12.Cu" signal "GND5")
		(28 "In13.Cu" signal "IN5")
		(30 "In14.Cu" signal "GND6")
		(32 "In15.Cu" signal "IN6")
		(34 "In16.Cu" signal "GND7")
		(2 "B.Cu" signal "BOTTOM")
		(9 "F.Adhes" user "F.Adhesive")
		(11 "B.Adhes" user "B.Adhesive")
		(13 "F.Paste" user "Package Geometry/Pastemask Top")
		(15 "B.Paste" user "Package Geometry/Pastemask Bottom")
		(5 "F.SilkS" user "Ref Des/Silkscreen Top")
		(7 "B.SilkS" user "Ref Des/Silkscreen Bottom")
		(1 "F.Mask" user "Board Geometry/Soldermask Top")
		(3 "B.Mask" user "Board Geometry/Soldermask Bottom")
		(17 "Dwgs.User" user "User.Drawings")
		(19 "Cmts.User" user "User.Comments")
		(21 "Eco1.User" user "User.Eco1")
		(23 "Eco2.User" user "User.Eco2")
		(25 "Edge.Cuts" user "Board Geometry/Outline")
		(27 "Margin" user)
		(31 "F.CrtYd" user "Package Geometry/Place Bound Top")
		(29 "B.CrtYd" user "Package Geometry/Place Bound Bottom")
		(35 "F.Fab" user "Ref Des/Assembly Top")
		(33 "B.Fab" user "Ref Des/Assembly Bottom")
	)
	(footprint ""
		(layer "F.Cu")
		(at 359.870248 -251.76988 90)
		(property "Reference" "U2"
			(at -74.416158 -44.488608 0)
			(unlocked yes)
			(layer "F.SilkS")
			(effects
				(font
					(size 1.6002 1.1938)
					(thickness 0.1524)
				)
				(justify left)
			)
		)
		(property "Value" ""
			(at 0 0 90)
			(layer "F.Fab")
			(effects
				(font
					(size 1.27 1.27)
				)
			)
		)
		(duplicate_pad_numbers_are_jumpers no)
		(pad "BM77" smd circle
			(at 26.030682 -2.999486 270)
			(size 0.4318 0.4318)
			(layers "F.Cu" "F.Mask" "F.Paste")
			(net "GND")
		)
		(pad "BM79" smd circle
			(at 27.658314 -2.999486 270)
			(size 0.4318 0.4318)
			(layers "F.Cu" "F.Mask" "F.Paste")
			(net "PVCCIN_CPU0")
		)
		(pad "BM81" smd circle
			(at 29.2862 -2.999486 270)
			(size 0.4318 0.4318)
			(layers "F.Cu" "F.Mask" "F.Paste")
			(net "PVCCIN_CPU0")
		)
		(pad "BM83" smd circle
			(at 30.914086 -2.999486 270)
			(size 0.4318 0.4318)
			(layers "F.Cu" "F.Mask" "F.Paste")
			(net "PVCCIN_CPU0")
		)
		(pad "BM85" smd circle
			(at 32.541718 -2.999486 270)
			(size 0.4318 0.4318)
			(layers "F.Cu" "F.Mask" "F.Paste")
			(net "PVCCIN_CPU0")
		)
		(pad "BM87" smd circle
			(at 34.169604 -2.999486 270)
			(size 0.4318 0.4318)
			(layers "F.Cu" "F.Mask" "F.Paste")
			(net "PVCCIN_CPU0")
		)
		(pad "BM89" smd circle
			(at 35.797236 -2.999486 270)
			(size 0.4318 0.4318)
			(layers "F.Cu" "F.Mask" "F.Paste")
			(net "PVCCIN_CPU0")
		)
		(pad "BM91" smd oval
			(at 37.425122 -2.999486)
			(size 0.381 0.4826)
			(drill
				(offset 0 -0.0508)
			)
			(layers "F.Cu" "F.Mask" "F.Paste")
			(net "PVCCIN_CPU0")
		)
		(pad "BN3" smd circle
			(at -35.797236 -2.639314 270)
			(size 0.4318 0.4318)
			(layers "F.Cu" "F.Mask" "F.Paste")
			(net "UPI_CPU0_CPU1_P0P1_DN<22>")
		)
		(pad "BN5" smd circle
			(at -34.169604 -2.639314 270)
			(size 0.4318 0.4318)
			(layers "F.Cu" "F.Mask" "F.Paste")
			(net "UPI_CPU1_CPU0_P1P0_DP<21>")
		)
		(pad "BN7" smd circle
			(at -32.541718 -2.639314 270)
			(size 0.4318 0.4318)
			(layers "F.Cu" "F.Mask" "F.Paste")
			(net "PVCCD_HV_CPU0")
		)
		(pad "BN9" smd circle
			(at -30.914086 -2.639314 270)
			(size 0.4318 0.4318)
			(layers "F.Cu" "F.Mask" "F.Paste")
			(net "P5E_CPU0_PE1_RX_DP<10>")
		)
		(pad "BN11" smd circle
			(at -29.2862 -2.639314 270)
			(size 0.4318 0.4318)
			(layers "F.Cu" "F.Mask" "F.Paste")
			(net "VSENSE_PVCCD_HV_CPU0_DN")
		)
		(pad "BN13" smd circle
			(at -27.658314 -2.639314 270)
			(size 0.4318 0.4318)
			(layers "F.Cu" "F.Mask" "F.Paste")
			(net "P5E_CPU0_PE1_TX_DN<11>")
		)
		(pad "BN15" smd circle
			(at -26.030682 -2.639314 270)
			(size 0.4318 0.4318)
			(layers "F.Cu" "F.Mask" "F.Paste")
			(net "PVCCINFAON_CPU0")
		)
		(pad "BN17" smd circle
			(at -24.402796 -2.639314 270)
			(size 0.4318 0.4318)
			(layers "F.Cu" "F.Mask" "F.Paste")
			(net "DMI_CPU0_PCH_RX_C_DP<5>")
		)
		(pad "BN19" smd circle
			(at -22.77491 -2.639314 270)
			(size 0.4318 0.4318)
			(layers "F.Cu" "F.Mask" "F.Paste")
			(net "PVNN_MAIN_CPU0")
		)
		(pad "BN21" smd circle
			(at -21.147278 -2.639314 270)
			(size 0.4318 0.4318)
			(layers "F.Cu" "F.Mask" "F.Paste")
			(net "NC_CPU0_PE0_APROBE<0>")
		)
		(pad "BN23" smd circle
			(at -19.519392 -2.639314 270)
			(size 0.4318 0.4318)
			(layers "F.Cu" "F.Mask" "F.Paste")
			(net "H_CPU0_BMCINIT_LVC1")
		)
		(pad "BN25" smd circle
			(at -17.89176 -2.639314 270)
			(size 0.4318 0.4318)
			(layers "F.Cu" "F.Mask" "F.Paste")
			(net "DBP_CPU0_MBP1_GTL_R_N")
		)
		(pad "BN27" smd circle
			(at -16.263874 -2.639314 270)
			(size 0.4318 0.4318)
			(layers "F.Cu" "F.Mask" "F.Paste")
			(net "TP_TRC_CPU0_PTI<12>")
		)
		(pad "BN29" smd circle
			(at -14.635988 -2.639314 270)
			(size 0.4318 0.4318)
			(layers "F.Cu" "F.Mask" "F.Paste")
			(net "TP_TRC_CPU0_PTI<14>")
		)
		(pad "BN31" smd circle
			(at -13.008356 -2.639314 270)
			(size 0.4318 0.4318)
			(layers "F.Cu" "F.Mask" "F.Paste")
			(net "GND")
		)
		(pad "BN33" smd circle
			(at -11.380724 -2.639314 270)
			(size 0.4318 0.4318)
			(layers "F.Cu" "F.Mask" "F.Paste")
			(net "PVCCIN_CPU0")
		)
		(pad "BN35" smd circle
			(at -9.752838 -2.639314 270)
			(size 0.4318 0.4318)
			(layers "F.Cu" "F.Mask" "F.Paste")
			(net "PVCCIN_CPU0")
		)
		(pad "BN37" smd circle
			(at -8.124952 -2.639314 270)
			(size 0.4318 0.4318)
			(layers "F.Cu" "F.Mask" "F.Paste")
			(net "PVCCIN_CPU0")
		)
		(pad "BN39" smd circle
			(at -6.49732 -2.639314 270)
			(size 0.4318 0.4318)
			(layers "F.Cu" "F.Mask" "F.Paste")
			(net "PVCCIN_CPU0")
		)
		(pad "BN41" smd circle
			(at -4.869434 -2.639314 270)
			(size 0.4318 0.4318)
			(layers "F.Cu" "F.Mask" "F.Paste")
			(net "PVCCIN_CPU0")
		)
		(pad "BN43" smd circle
			(at -3.241802 -2.639314 270)
			(size 0.4318 0.4318)
			(layers "F.Cu" "F.Mask" "F.Paste")
			(net "PVCCIN_CPU0")
		)
		(pad "BN45" smd circle
			(at -1.613916 -2.639314 270)
			(size 0.4318 0.4318)
			(layers "F.Cu" "F.Mask" "F.Paste")
			(net "PVCCIN_CPU0")
		)
		(pad "BN48" smd circle
			(at 2.427732 -2.529586 270)
			(size 0.4318 0.4318)
			(layers "F.Cu" "F.Mask" "F.Paste")
			(net "PVCCIN_CPU0")
		)
		(pad "BN50" smd circle
			(at 4.055618 -2.529586 270)
			(size 0.4318 0.4318)
			(layers "F.Cu" "F.Mask" "F.Paste")
			(net "PVCCIN_CPU0")
		)
		(pad "BN52" smd circle
			(at 5.68325 -2.529586 270)
			(size 0.4318 0.4318)
			(layers "F.Cu" "F.Mask" "F.Paste")
			(net "PVCCIN_CPU0")
		)
		(pad "BN54" smd circle
			(at 7.311136 -2.529586 270)
			(size 0.4318 0.4318)
			(layers "F.Cu" "F.Mask" "F.Paste")
			(net "PVCCIN_CPU0")
		)
		(pad "BN56" smd circle
			(at 8.939022 -2.529586 270)
			(size 0.4318 0.4318)
			(layers "F.Cu" "F.Mask" "F.Paste")
			(net "PVCCIN_CPU0")
		)
		(pad "BN58" smd circle
			(at 10.566654 -2.529586 270)
			(size 0.4318 0.4318)
			(layers "F.Cu" "F.Mask" "F.Paste")
			(net "PVCCIN_CPU0")
		)
		(pad "BN60" smd circle
			(at 12.19454 -2.529586 270)
			(size 0.4318 0.4318)
			(layers "F.Cu" "F.Mask" "F.Paste")
			(net "PVCCIN_CPU0")
		)
		(pad "BN62" smd circle
			(at 13.822426 -2.529586 270)
			(size 0.4318 0.4318)
			(layers "F.Cu" "F.Mask" "F.Paste")
			(net "GND")
		)
		(pad "BN64" smd circle
			(at 15.450058 -2.529586 270)
			(size 0.4318 0.4318)
			(layers "F.Cu" "F.Mask" "F.Paste")
			(net "FM_CPU0_PKGID2")
		)
		(pad "BN66" smd circle
			(at 17.07769 -2.529586 270)
			(size 0.4318 0.4318)
			(layers "F.Cu" "F.Mask" "F.Paste")
			(net "TP_TRC_CPU0_PTI<31>")
		)
		(pad "BN68" smd circle
			(at 18.705576 -2.529586 270)
			(size 0.4318 0.4318)
			(layers "F.Cu" "F.Mask" "F.Paste")
			(net "TP_TRC_CPU0_PTI<26>")
		)
		(pad "BN70" smd circle
			(at 20.333462 -2.529586 270)
			(size 0.4318 0.4318)
			(layers "F.Cu" "F.Mask" "F.Paste")
			(net "GND")
		)
		(pad "BN72" smd circle
			(at 21.961094 -2.529586 270)
			(size 0.4318 0.4318)
			(layers "F.Cu" "F.Mask" "F.Paste")
			(net "UPI_CPU0_CPU1_P2P2_DP<0>")
		)
		(pad "BN74" smd circle
			(at 23.58898 -2.529586 270)
			(size 0.4318 0.4318)
			(layers "F.Cu" "F.Mask" "F.Paste")
			(net "UPI_CPU1_CPU0_P2P2_DP<2>")
		)
		(pad "BN76" smd circle
			(at 25.216612 -2.529586 270)
			(size 0.4318 0.4318)
			(layers "F.Cu" "F.Mask" "F.Paste")
			(net "UPI_CPU1_CPU0_P2P2_DN<4>")
		)
		(pad "BN78" smd circle
			(at 26.844498 -2.529586 270)
			(size 0.4318 0.4318)
			(layers "F.Cu" "F.Mask" "F.Paste")
			(net "PVCCIN_CPU0")
		)
		(pad "BN80" smd circle
			(at 28.472384 -2.529586 270)
			(size 0.4318 0.4318)
			(layers "F.Cu" "F.Mask" "F.Paste")
			(net "PVCCIN_CPU0")
		)
		(pad "BN82" smd circle
			(at 30.100016 -2.529586 270)
			(size 0.4318 0.4318)
			(layers "F.Cu" "F.Mask" "F.Paste")
			(net "PVCCIN_CPU0")
		)
		(pad "BN84" smd circle
			(at 31.727902 -2.529586 270)
			(size 0.4318 0.4318)
			(layers "F.Cu" "F.Mask" "F.Paste")
			(net "PVCCIN_CPU0")
		)
		(pad "BN86" smd circle
			(at 33.355534 -2.529586 270)
			(size 0.4318 0.4318)
			(layers "F.Cu" "F.Mask" "F.Paste")
			(net "PVCCIN_CPU0")
		)
		(pad "BN88" smd circle
			(at 34.98342 -2.529586 270)
			(size 0.4318 0.4318)
			(layers "F.Cu" "F.Mask" "F.Paste")
			(net "PVCCIN_CPU0")
		)
		(pad "BN90" smd oval
			(at 36.611306 -2.529586)
			(size 0.381 0.4826)
			(drill
				(offset 0 -0.0508)
			)
			(layers "F.Cu" "F.Mask" "F.Paste")
			(net "PVCCIN_CPU0")
		)
		(pad "BP2" smd oval
			(at -36.611306 -2.169668 180)
			(size 0.381 0.4826)
			(drill
				(offset 0 -0.0508)
			)
			(layers "F.Cu" "F.Mask" "F.Paste")
			(net "GND")
		)
		(pad "BP4" smd circle
			(at -34.98342 -2.169668 270)
			(size 0.4318 0.4318)
			(layers "F.Cu" "F.Mask" "F.Paste")
			(net "GND")
		)
		(pad "BP6" smd circle
			(at -33.355534 -2.169668 270)
			(size 0.4318 0.4318)
			(layers "F.Cu" "F.Mask" "F.Paste")
			(net "UPI_CPU1_CPU0_P1P0_DP<22>")
		)
		(pad "BP8" smd circle
			(at -31.727902 -2.169668 270)
			(size 0.4318 0.4318)
			(layers "F.Cu" "F.Mask" "F.Paste")
			(net "GND")
		)
		(pad "BP10" smd circle
			(at -30.100016 -2.169668 270)
			(size 0.4318 0.4318)
			(layers "F.Cu" "F.Mask" "F.Paste")
			(net "P5E_CPU0_PE1_RX_DN<10>")
		)
		(pad "BP12" smd circle
			(at -28.472384 -2.169668 270)
			(size 0.4318 0.4318)
			(layers "F.Cu" "F.Mask" "F.Paste")
			(net "GND")
		)
		(pad "BP14" smd circle
			(at -26.844498 -2.169668 270)
			(size 0.4318 0.4318)
			(layers "F.Cu" "F.Mask" "F.Paste")
			(net "P5E_CPU0_PE1_TX_DN<10>")
		)
		(pad "BP16" smd circle
			(at -25.216612 -2.169668 270)
			(size 0.4318 0.4318)
			(layers "F.Cu" "F.Mask" "F.Paste")
			(net "GND")
		)
		(pad "BP18" smd circle
			(at -23.58898 -2.169668 270)
			(size 0.4318 0.4318)
			(layers "F.Cu" "F.Mask" "F.Paste")
			(net "DMI_CPU0_PCH_RX_C_DP<6>")
		)
		(pad "BP20" smd circle
			(at -21.961094 -2.169668 270)
			(size 0.4318 0.4318)
			(layers "F.Cu" "F.Mask" "F.Paste")
			(net "GND")
		)
		(pad "BP22" smd circle
			(at -20.333462 -2.169668 270)
			(size 0.4318 0.4318)
			(layers "F.Cu" "F.Mask" "F.Paste")
			(net "NC_CPU0_MDFI_DIE00_EW0")
		)
		(pad "BP24" smd circle
			(at -18.705576 -2.169668 270)
			(size 0.4318 0.4318)
			(layers "F.Cu" "F.Mask" "F.Paste")
			(net "H_CPU0_CATERR_LVC1_R_N")
		)
		(pad "BP26" smd circle
			(at -17.07769 -2.169668 270)
			(size 0.4318 0.4318)
			(layers "F.Cu" "F.Mask" "F.Paste")
			(net "H_CPU0_PRDY_QS_GTL_R_N")
		)
		(pad "BP28" smd circle
			(at -15.450058 -2.169668 270)
			(size 0.4318 0.4318)
			(layers "F.Cu" "F.Mask" "F.Paste")
			(net "TP_TRC_CPU0_PTI<13>")
		)
		(pad "BP30" smd circle
			(at -13.822426 -2.169668 270)
			(size 0.4318 0.4318)
			(layers "F.Cu" "F.Mask" "F.Paste")
			(net "TP_TRC_CPU0_PTI<15>")
		)
		(pad "BP32" smd circle
			(at -12.19454 -2.169668 270)
			(size 0.4318 0.4318)
			(layers "F.Cu" "F.Mask" "F.Paste")
			(net "PVCCIN_CPU0")
		)
		(pad "BP34" smd circle
			(at -10.566654 -2.169668 270)
			(size 0.4318 0.4318)
			(layers "F.Cu" "F.Mask" "F.Paste")
			(net "PVCCIN_CPU0")
		)
		(pad "BP36" smd circle
			(at -8.939022 -2.169668 270)
			(size 0.4318 0.4318)
			(layers "F.Cu" "F.Mask" "F.Paste")
			(net "PVCCIN_CPU0")
		)
		(pad "BP38" smd circle
			(at -7.311136 -2.169668 270)
			(size 0.4318 0.4318)
			(layers "F.Cu" "F.Mask" "F.Paste")
			(net "PVCCIN_CPU0")
		)
		(pad "BP40" smd circle
			(at -5.68325 -2.169668 270)
			(size 0.4318 0.4318)
			(layers "F.Cu" "F.Mask" "F.Paste")
			(net "PVCCIN_CPU0")
		)
		(pad "BP42" smd circle
			(at -4.055618 -2.169668 270)
			(size 0.4318 0.4318)
			(layers "F.Cu" "F.Mask" "F.Paste")
			(net "PVCCIN_CPU0")
		)
		(pad "BP44" smd circle
			(at -2.427732 -2.169668 270)
			(size 0.4318 0.4318)
			(layers "F.Cu" "F.Mask" "F.Paste")
			(net "PVCCIN_CPU0")
		)
		(pad "BP47" smd circle
			(at 1.613916 -2.059686 270)
			(size 0.4318 0.4318)
			(layers "F.Cu" "F.Mask" "F.Paste")
			(net "PVCCIN_CPU0")
		)
		(pad "BP49" smd circle
			(at 3.241802 -2.059686 270)
			(size 0.4318 0.4318)
			(layers "F.Cu" "F.Mask" "F.Paste")
			(net "PVCCIN_CPU0")
		)
		(pad "BP51" smd circle
			(at 4.869434 -2.059686 270)
			(size 0.4318 0.4318)
			(layers "F.Cu" "F.Mask" "F.Paste")
			(net "PVCCIN_CPU0")
		)
		(pad "BP53" smd circle
			(at 6.49732 -2.059686 270)
			(size 0.4318 0.4318)
			(layers "F.Cu" "F.Mask" "F.Paste")
			(net "PVCCIN_CPU0")
		)
		(pad "BP55" smd circle
			(at 8.124952 -2.059686 270)
			(size 0.4318 0.4318)
			(layers "F.Cu" "F.Mask" "F.Paste")
			(net "PVCCIN_CPU0")
		)
		(pad "BP57" smd circle
			(at 9.752838 -2.059686 270)
			(size 0.4318 0.4318)
			(layers "F.Cu" "F.Mask" "F.Paste")
			(net "PVCCIN_CPU0")
		)
		(pad "BP59" smd circle
			(at 11.380724 -2.059686 270)
			(size 0.4318 0.4318)
			(layers "F.Cu" "F.Mask" "F.Paste")
			(net "PVCCIN_CPU0")
		)
		(pad "BP61" smd circle
			(at 13.008356 -2.059686 270)
			(size 0.4318 0.4318)
			(layers "F.Cu" "F.Mask" "F.Paste")
			(net "PVCCIN_CPU0")
		)
		(pad "BP63" smd circle
			(at 14.635988 -2.059686 270)
			(size 0.4318 0.4318)
			(layers "F.Cu" "F.Mask" "F.Paste")
			(net "GND")
		)
		(pad "BP65" smd circle
			(at 16.263874 -2.059686 270)
			(size 0.4318 0.4318)
			(layers "F.Cu" "F.Mask" "F.Paste")
			(net "NC_CPU0_SOC_SPARE5")
		)
		(pad "BP67" smd circle
			(at 17.89176 -2.059686 270)
			(size 0.4318 0.4318)
			(layers "F.Cu" "F.Mask" "F.Paste")
			(net "NC_CPU0_VIEWPIN_DIE01<1>")
		)
		(pad "BP69" smd circle
			(at 19.519392 -2.059686 270)
			(size 0.4318 0.4318)
			(layers "F.Cu" "F.Mask" "F.Paste")
			(net "NC_CPU0_VIEWPIN_DIE01<0>")
		)
		(pad "BP71" smd circle
			(at 21.147278 -2.059686 270)
			(size 0.4318 0.4318)
			(layers "F.Cu" "F.Mask" "F.Paste")
			(net "GND")
		)
		(pad "BP73" smd circle
			(at 22.77491 -2.059686 270)
			(size 0.4318 0.4318)
			(layers "F.Cu" "F.Mask" "F.Paste")
			(net "GND")
		)
		(pad "BP75" smd circle
			(at 24.402796 -2.059686 270)
			(size 0.4318 0.4318)
			(layers "F.Cu" "F.Mask" "F.Paste")
			(net "GND")
		)
		(pad "BP77" smd circle
			(at 26.030682 -2.059686 270)
			(size 0.4318 0.4318)
			(layers "F.Cu" "F.Mask" "F.Paste")
			(net "GND")
		)
		(pad "BP79" smd circle
			(at 27.658314 -2.059686 270)
			(size 0.4318 0.4318)
			(layers "F.Cu" "F.Mask" "F.Paste")
			(net "PVCCIN_CPU0")
		)
		(pad "BP81" smd circle
			(at 29.2862 -2.059686 270)
			(size 0.4318 0.4318)
			(layers "F.Cu" "F.Mask" "F.Paste")
			(net "PVCCIN_CPU0")
		)
		(pad "BP83" smd circle
			(at 30.914086 -2.059686 270)
			(size 0.4318 0.4318)
			(layers "F.Cu" "F.Mask" "F.Paste")
			(net "PVCCIN_CPU0")
		)
		(pad "BP85" smd circle
			(at 32.541718 -2.059686 270)
			(size 0.4318 0.4318)
			(layers "F.Cu" "F.Mask" "F.Paste")
			(net "PVCCIN_CPU0")
		)
		(pad "BP87" smd circle
			(at 34.169604 -2.059686 270)
			(size 0.4318 0.4318)
			(layers "F.Cu" "F.Mask" "F.Paste")
			(net "PVCCIN_CPU0")
		)
		(pad "BP89" smd circle
			(at 35.797236 -2.059686 270)
			(size 0.4318 0.4318)
			(layers "F.Cu" "F.Mask" "F.Paste")
			(net "PVCCIN_CPU0")
		)
		(pad "BR3" smd circle
			(at -35.797236 -1.699514 270)
			(size 0.4318 0.4318)
			(layers "F.Cu" "F.Mask" "F.Paste")
			(net "UPI_CPU0_CPU1_P0P1_DP<22>")
		)
		(pad "BR5" smd circle
			(at -34.169604 -1.699514 270)
			(size 0.4318 0.4318)
			(layers "F.Cu" "F.Mask" "F.Paste")
			(net "GND")
		)
		(pad "BR7" smd circle
			(at -32.541718 -1.699514 270)
			(size 0.4318 0.4318)
			(layers "F.Cu" "F.Mask" "F.Paste")
			(net "UPI_CPU1_CPU0_P1P0_DN<22>")
		)
		(pad "BR9" smd circle
			(at -30.914086 -1.699514 270)
			(size 0.4318 0.4318)
			(layers "F.Cu" "F.Mask" "F.Paste")
			(net "GND")
		)
		(pad "BR11" smd circle
			(at -29.2862 -1.699514 270)
			(size 0.4318 0.4318)
			(layers "F.Cu" "F.Mask" "F.Paste")
			(net "P5E_CPU0_PE1_RX_DN<9>")
		)
		(pad "BR13" smd circle
			(at -27.658314 -1.699514 270)
			(size 0.4318 0.4318)
			(layers "F.Cu" "F.Mask" "F.Paste")
			(net "GND")
		)
		(pad "BR15" smd circle
			(at -26.030682 -1.699514 270)
			(size 0.4318 0.4318)
			(layers "F.Cu" "F.Mask" "F.Paste")
			(net "P5E_CPU0_PE1_TX_DP<10>")
		)
		(pad "BR17" smd circle
			(at -24.402796 -1.699514 270)
			(size 0.4318 0.4318)
			(layers "F.Cu" "F.Mask" "F.Paste")
			(net "GND")
		)
		(pad "BR19" smd circle
			(at -22.77491 -1.699514 270)
			(size 0.4318 0.4318)
			(layers "F.Cu" "F.Mask" "F.Paste")
			(net "DMI_CPU0_PCH_RX_C_DN<6>")
		)
		(pad "BR21" smd circle
			(at -21.147278 -1.699514 270)
			(size 0.4318 0.4318)
			(layers "F.Cu" "F.Mask" "F.Paste")
			(net "NC_CPU0_MDFI_DIE00_EW1")
		)
		(pad "BR23" smd circle
			(at -19.519392 -1.699514 270)
			(size 0.4318 0.4318)
			(layers "F.Cu" "F.Mask" "F.Paste")
			(net "TP_CPU0_BR23")
		)
	)
)
